G04 ================== begin FILE IDENTIFICATION RECORD ==================*
G04 Layout Name:  12004-1.brd*
G04 Film Name:    P_OUTLINE*
G04 File Format:  Gerber RS274X*
G04 File Origin:  Cadence Allegro 16.2-S033*
G04 Origin Date:  Tue Oct 16 14:35:42 2012*
G04 *
G04 Layer:  BOARD GEOMETRY/PANEL_OUTLINE*
G04 *
G04 Offset:    (0.00 0.00)*
G04 Mirror:    No*
G04 Mode:      Positive*
G04 Rotation:  0*
G04 FullContactRelief:  No*
G04 UndefLineWidth:     6.00*
G04 ================== end FILE IDENTIFICATION RECORD ====================*
%FSLAX35Y35*MOIN*%
%IR0*IPPOS*OFA0.00000B0.00000*MIA0B0*SFA1.00000B1.00000*%
%ADD10C,.006*%
G75*
%LPD*%
G75*
G54D10*
G01X-1003937Y-3937D02*
G03X-1000000Y-7874I3937J0D01*
G01X-1031496Y-31496D02*
G03X-1027559Y-35433I3937J0D01*
G01X-986221Y-7874D02*
G03Y0I0J3937D01*
G01Y-7874D02*
X-1000000D01*
G01X-1027559Y-35433D02*
X791338D01*
G01X-1031496Y95866D02*
Y-31496D01*
G01X-996063Y3937D02*
G03X-992126Y0I3937J0D01*
G01X-996063Y39370D02*
G03X-1003937I-3937J0D01*
G01X-996063Y3937D02*
G03X-992126Y0I3937J0D01*
G01D02*
X-318898D01*
G01D02*
X-992126D01*
G01X-955512D02*
X-986221D01*
G01X-996063Y3937D02*
Y103740D01*
G01Y39370D02*
Y70079D01*
G01X-1003937Y-3937D02*
Y39370D01*
G01X-1027559Y99803D02*
G03X-1031496Y95866I0J-3937D01*
G01X-1003937D02*
G03X-1007874Y99803I-3937J0D01*
G01X-996063Y103740D02*
G03X-1000000Y107677I-3937J0D01*
G01X-1003937Y70079D02*
G03X-996063I3937J0D01*
G01X-1029528Y107677D02*
X-1000000D01*
G01X-1007874Y99803D02*
X-1027559D01*
G01X-1003937Y70079D02*
Y95866D01*
G01X-1031496Y109646D02*
X-1029528Y107677D01*
G01X-1031496Y109646D02*
Y134055D01*
G01X-1002166Y136024D02*
G03Y143504I0J3740D01*
G01X-1000000Y187599D02*
G03X-996063Y191536I0J3937D01*
G01X-1029528Y187599D02*
X-1000000D01*
G01X-1029528Y143504D02*
X-1002166D01*
G01X-1029528Y136024D02*
X-1002166D01*
G01X-1029528D02*
X-1031496Y134055D01*
G01X-1029528Y187599D02*
X-1031496Y185630D01*
G01Y145473D02*
X-1029528Y143504D01*
G01X-996063Y261221D02*
Y191536D01*
G01X-1031496Y145473D02*
Y185630D01*
G01X-996063Y261221D02*
G03X-1000000Y265158I-3937J0D01*
G01X-1029528D02*
X-1000000D01*
G01X-1031496Y267126D02*
X-1029528Y265158D01*
G01X-1031496Y267126D02*
Y543504D01*
G01X-1002166Y545473D02*
G03Y552953I0J3740D01*
G01X-1029528D02*
X-1002166D01*
G01X-1029528Y545473D02*
X-1002166D01*
G01X-1031496Y554922D02*
X-1029528Y552953D01*
G01Y545473D02*
X-1031496Y543504D01*
G01Y554922D02*
Y595079D01*
G01X-1007874Y604922D02*
G03X-1003937Y608859I0J3937D01*
G01X-1031496D02*
G03X-1027559Y604922I3937J0D01*
G01X-1000000Y597048D02*
G03X-996063Y600985I0J3937D01*
G01X-1027559Y604922D02*
X-1007874D01*
G01X-1029528Y597048D02*
X-1000000D01*
G01X-1029528D02*
X-1031496Y595079D01*
G01X-996063Y921260D02*
Y600985D01*
G01X-1003937Y608859D02*
Y708662D01*
G01X-1031496Y956693D02*
Y608859D01*
G01X-1003937Y739370D02*
G03X-996063I3937J0D01*
G01Y708662D02*
G03X-1003937I-3937J0D01*
G01X-996063D02*
Y739370D01*
G01X-1003937D02*
Y929134D01*
G01X-992126Y925197D02*
G03X-996063Y921260I0J-3937D01*
G01X-1000000Y933071D02*
G03X-1003937Y929134I0J-3937D01*
G01X-986221Y925197D02*
G03Y933071I0J3937D01*
G01X-1027559Y960630D02*
G03X-1031496Y956693I0J-3937D01*
G01X-992126Y925197D02*
G03X-996063Y921260I0J-3937D01*
G01X791338Y960630D02*
X-1027559D01*
G01X-1000000Y933071D02*
X-986221D01*
G01X-992126Y925197D02*
X-240158D01*
G01X-986221D02*
X-955512D01*
G01X-992126D02*
X-240158D01*
G01X-955512Y0D02*
G03Y-7874I0J-3937D01*
G01X-769685D02*
X-955512D01*
G01Y933071D02*
G03Y925197I0J-3937D01*
G01Y933071D02*
X-750000D01*
G01X-769685Y-7874D02*
G03Y0I0J3937D01*
G01X-738977D02*
X-769685D01*
G01X-738977D02*
G03Y-7874I0J-3937D01*
G01X-522835D02*
X-738977D01*
G01X-719292Y933071D02*
G03Y925197I0J-3937D01*
G01X-750000D02*
G03Y933071I0J3937D01*
G01X-719292D02*
X-512992D01*
G01X-750000Y925197D02*
X-719292D01*
G01X-522835Y-7874D02*
G03Y0I0J3937D01*
G01X-492126D02*
G03Y-7874I0J-3937D01*
G01X-365355D02*
X-492126D01*
G01Y0D02*
X-522835D01*
G01X-482284Y933071D02*
G03Y925197I0J-3937D01*
G01X-512992D02*
G03Y933071I0J3937D01*
G01Y925197D02*
X-482284D01*
G01Y933071D02*
X-316142D01*
G01X-365355Y-7874D02*
G03Y0I0J3937D01*
G01X-334646D02*
X-365355D01*
G01X-311024Y-7874D02*
G03X-307087Y-3937I0J3937D01*
G01X-334646Y0D02*
G03Y-7874I0J-3937D01*
G01X-311024D02*
X-334646D01*
G01X-318898Y0D02*
G03X-314961Y3937I0J3937D01*
G01X-274410Y31595D02*
G03X-270473Y35532I0J3937D01*
G01X-303150Y31595D02*
G03X-307087Y27658I0J-3937D01*
G01X-318898Y0D02*
G03X-314961Y3937I0J3937D01*
G01X-307087Y27658D02*
Y-3937D01*
G01X-314961Y133859D02*
Y3937D01*
G01Y133859D02*
Y3937D01*
G01X-274410Y31595D02*
X-303150D01*
G01X-311024Y137796D02*
G03X-314961Y133859I0J-3937D01*
G01X-311024Y137796D02*
G03X-314961Y133859I0J-3937D01*
G01X-240158Y137796D02*
X-311024D01*
G01X-240158D02*
X-311024D01*
G01X-285433Y933071D02*
G03Y925197I0J-3937D01*
G01X-316142D02*
G03Y933071I0J3937D01*
G01X-285433D02*
X-224410D01*
G01X-316142Y925197D02*
X-285433D01*
G01X-270473Y125985D02*
Y35532D01*
G01X-266536Y129922D02*
G03X-270473Y125985I0J-3937D01*
G01X-260630Y129922D02*
G03Y137796I0J3937D01*
G01X-244882D02*
G03Y129922I0J-3937D01*
G01X-240158D02*
G03X-228347Y141733I0J11811D01*
G01X-260630Y129922D02*
X-266536D01*
G01X-240158D02*
X-244882D01*
G01X-240158Y137796D02*
G03X-236221Y141733I0J3937D01*
G01X-240158Y137796D02*
G03X-236221Y141733I0J3937D01*
G01X-228347Y368701D02*
Y141733D01*
G01X-236221Y413386D02*
Y141733D01*
G01X-244882Y137796D02*
X-260630D01*
G01X-204725Y409449D02*
G03X-208662Y405512I0J-3937D01*
G01X-232284Y417323D02*
G03X-236221Y413386I0J-3937D01*
G01X-232284Y417323D02*
G03X-236221Y413386I0J-3937D01*
G01X-212599Y372638D02*
G03X-208662Y376575I0J3937D01*
G01X-224410Y372638D02*
G03X-228347Y368701I0J-3937D01*
G01X-181103Y409449D02*
X-204725D01*
G01X-212599Y372638D02*
X-224410D01*
G01X-208662Y405512D02*
Y376575D01*
G01X-232284Y417323D02*
X-181103D01*
G01X-232284D02*
X-181103D01*
G01X-236221Y716536D02*
G03X-232284Y712599I3937J0D01*
G01X-224410Y724410D02*
G03X-220473Y720473I3937J0D01*
G01X-236221Y716536D02*
G03X-232284Y712599I3937J0D01*
G01X-220473Y720473D02*
X-96418D01*
G01Y712599D02*
X-232284D01*
G01X-96418D02*
X-232284D01*
G01X-224410Y933071D02*
Y724410D01*
G01X-236221Y921260D02*
Y716536D01*
G01Y921260D02*
G03X-240158Y925197I-3937J0D01*
G01X-236221Y921260D02*
G03X-240158Y925197I-3937J0D01*
G01X-143740Y216536D02*
G03X-139803Y212599I3937J0D01*
G01X-143740Y262205D02*
G03X-151614I-3937J0D01*
G01X-143740Y216536D02*
G03X-139803Y212599I3937J0D01*
G01X-151614Y216536D02*
G03X-139803Y204725I11811J0D01*
G01X-143740Y262205D02*
Y292914D01*
G01Y338583D02*
Y216536D01*
G01Y338583D02*
Y216536D01*
G01X-151614D02*
Y262205D01*
G01X-139803Y212599D02*
X-3937D01*
G01X-139803D02*
X-3937D01*
G01X-15748Y204725D02*
X-139803D01*
G01Y342520D02*
G03X-143740Y338583I0J-3937D01*
G01X-139803Y342520D02*
G03X-143740Y338583I0J-3937D01*
G01X-139803Y350394D02*
G03X-151614Y338583I0J-11811D01*
G01Y292914D02*
G03X-143740I3937J0D01*
G01X-151614D02*
Y338583D01*
G01X-62992Y342520D02*
X-139803D01*
G01X-62992D02*
X-139803D01*
G01X-181103Y409449D02*
G03X-169292Y421260I0J11811D01*
G01X-139803Y350394D02*
X-70866D01*
G01X-177166Y467717D02*
G03X-169292I3937J0D01*
G01X-181103Y417323D02*
G03X-177166Y421260I0J3937D01*
G01X-169292Y437008D02*
G03X-177166I-3937J0D01*
G01X-181103Y417323D02*
G03X-177166Y421260I0J3937D01*
G01X-169292Y437008D02*
Y421260D01*
G01Y570866D02*
Y467717D01*
G01X-177166Y421260D02*
Y578740D01*
G01Y421260D02*
Y578740D01*
G01Y467717D02*
Y437008D01*
G01X-173229Y582677D02*
G03X-177166Y578740I0J-3937D01*
G01X-165355Y574803D02*
G03X-169292Y570866I0J-3937D01*
G01X-173229Y582677D02*
G03X-177166Y578740I0J-3937D01*
G01X-173229Y582677D02*
X-96418D01*
G01X-173229D02*
X-96418D01*
G01Y574803D02*
X-165355D01*
G01X-62992Y342520D02*
G03X-59055Y346457I0J3937D01*
G01X-62992Y342520D02*
G03X-59055Y346457I0J3937D01*
G01X-70866Y350394D02*
G03X-66929Y354331I0J3937D01*
G01D02*
Y457481D01*
G01Y488189D02*
G03X-59055I3937J0D01*
G01Y457481D02*
G03X-66929I-3937J0D01*
G01X-55118Y515748D02*
G03X-66929Y503937I0J-11811D01*
G01Y488189D02*
Y503937D01*
G01X-96418Y582677D02*
G03X-92481Y586615I0J3937D01*
G01X-96418Y582677D02*
G03X-92481Y586615I0J3937D01*
G01X-96418Y574803D02*
G03X-84607Y586615I0J11811D01*
G01Y632284D02*
Y586615D01*
G01X-92481D02*
Y708662D01*
G01Y586615D02*
Y708662D01*
G01Y662992D02*
G03X-84607I3937J0D01*
G01Y632284D02*
G03X-92481I-3937J0D01*
G01X-84607Y708662D02*
Y662992D01*
G01X-92481D02*
Y632284D01*
G01Y708662D02*
G03X-96418Y712599I-3937J0D01*
G01X-92481Y708662D02*
G03X-96418Y712599I-3937J0D01*
G01X-84607Y708662D02*
G03X-96418Y720473I-11811J0D01*
G01X-11811Y-3937D02*
G03X-7874Y-7874I3937J0D01*
G01X31496D02*
X-7874D01*
G01X0Y3937D02*
G03X3937Y0I3937J0D01*
G01X0Y3937D02*
G03X3937Y0I3937J0D01*
G01X0Y3937D02*
Y208662D01*
G01X-11811Y-3937D02*
Y200788D01*
G01X755905Y0D02*
X3937D01*
G01X755905D02*
X3937D01*
G01X-11811Y200788D02*
G03X-15748Y204725I-3937J0D01*
G01X0Y208662D02*
G03X-3937Y212599I-3937J0D01*
G01X0Y208662D02*
G03X-3937Y212599I-3937J0D01*
G01X-59055Y503937D02*
Y346457D01*
G01Y503937D02*
Y346457D01*
G01Y488189D02*
Y457481D01*
G01X-23622Y552559D02*
G03X-27559Y548622I0J-3937D01*
G01X-11811Y552559D02*
G03X-7874Y556496I0J3937D01*
G01X-3937Y507874D02*
G03X0Y511811I0J3937D01*
G01X-3937Y507874D02*
G03X0Y511811I0J3937D01*
G01X-55118Y507874D02*
G03X-59055Y503937I0J-3937D01*
G01X-31496Y515748D02*
G03X-27559Y519685I0J3937D01*
G01X-55118Y507874D02*
G03X-59055Y503937I0J-3937D01*
G01X-23622Y552559D02*
X-11811D01*
G01X0Y511811D02*
Y783465D01*
G01X-27559Y519685D02*
Y548622D01*
G01X-55118Y515748D02*
X-31496D01*
G01X-3937Y507874D02*
X-55118D01*
G01X-3937D02*
X-55118D01*
G01X-7874Y556496D02*
Y783465D01*
G01X3937Y787402D02*
G03X0Y783465I0J-3937D01*
G01X3937Y787402D02*
G03X0Y783465I0J-3937D01*
G01X3937Y795276D02*
G03X-7874Y783465I0J-11811D01*
G01X3937Y795276D02*
X8661D01*
G01X3937Y787402D02*
X74803D01*
G01X3937D02*
X74803D01*
G01X62204Y0D02*
G03Y-7874I0J-3937D01*
G01X31496D02*
G03Y0I0J3937D01*
G01X267716Y-7874D02*
X62204D01*
G01Y0D02*
X31496D01*
G01X74803Y787402D02*
G03X78740Y791339I0J3937D01*
G01X30315Y795276D02*
G03X34252Y799213I0J3937D01*
G01X24409Y795276D02*
G03Y787402I0J-3937D01*
G01X8661D02*
G03Y795276I0J3937D01*
G01X74803Y787402D02*
G03X78740Y791339I0J3937D01*
G01X24409Y795276D02*
X30315D01*
G01X24409Y787402D02*
X8661D01*
G01X34252Y799213D02*
Y889666D01*
G01X38189Y893603D02*
G03X34252Y889666I0J-3937D01*
G01X66929Y893603D02*
G03X70866Y897540I0J3937D01*
G01X38189Y893603D02*
X66929D01*
G01X70866Y897540D02*
Y929134D01*
G01X74803Y933071D02*
G03X70866Y929134I0J-3937D01*
G01X74803Y933071D02*
X88582D01*
G01X78740Y791339D02*
Y921260D01*
G01Y791339D02*
Y921260D01*
G01X119291Y933071D02*
G03Y925197I0J-3937D01*
G01X82677D02*
G03X78740Y921260I0J-3937D01*
G01X88582Y925197D02*
G03Y933071I0J3937D01*
G01X82677Y925197D02*
G03X78740Y921260I0J-3937D01*
G01X119291Y933071D02*
X305118D01*
G01X82677Y925197D02*
X755905D01*
G01X82677D02*
X755905D01*
G01X119291D02*
X88582D01*
G01X267716Y-7874D02*
G03Y0I0J3937D01*
G01X298425D02*
X267716D01*
G01X298425D02*
G03Y-7874I0J-3937D01*
G01X483071D02*
X298425D01*
G01X335827Y933071D02*
G03Y925197I0J-3937D01*
G01X305118D02*
G03Y933071I0J3937D01*
G01X335827D02*
X522441D01*
G01X335827Y925197D02*
X305118D01*
G01X483071Y-7874D02*
G03Y0I0J3937D01*
G01X513779D02*
X483071D01*
G01X513779D02*
G03Y-7874I0J-3937D01*
G01X719291D02*
X513779D01*
G01X553149Y933071D02*
G03Y925197I0J-3937D01*
G01X522441D02*
G03Y933071I0J3937D01*
G01X553149D02*
X719291D01*
G01X553149Y925197D02*
X522441D01*
G01X763779Y-7874D02*
G03X767716Y-3937I0J3937D01*
G01X719291Y-7874D02*
G03Y0I0J3937D01*
G01X750000D02*
G03Y-7874I0J-3937D01*
G01X763779D02*
X750000D01*
G01X755905Y0D02*
G03X759842Y3937I0J3937D01*
G01X755905Y0D02*
G03X759842Y3937I0J3937D01*
G01X767716Y185827D02*
Y-3937D01*
G01X759842Y3937D02*
Y324213D01*
G01X750000Y0D02*
X719291D01*
G01X767716Y185827D02*
G03X759842I-3937J0D01*
G01Y216536D02*
Y185827D01*
G01Y216536D02*
G03X767716I3937J0D01*
G01Y316339D02*
Y216536D01*
G01X771653Y320276D02*
G03X767716Y316339I0J-3937D01*
G01X763779Y328150D02*
G03X759842Y324213I0J-3937D01*
G01X793307Y328150D02*
X763779D01*
G01X791338Y320276D02*
X771653D01*
G01X765945Y379725D02*
G03Y372244I0J-3741D01*
G01X793307Y379725D02*
X765945D01*
G01X793307Y372244D02*
X765945D01*
G01X759842Y663977D02*
G03X763779Y660040I3937J0D01*
G01X759842Y663977D02*
Y733662D01*
G01X793307Y660040D02*
X763779D01*
G01Y737599D02*
G03X759842Y733662I0J-3937D01*
G01X793307Y737599D02*
X763779D01*
G01X765945Y789174D02*
G03Y781693I0J-3740D01*
G01X767716Y829331D02*
G03X771653Y825394I3937J0D01*
G01X759842Y821457D02*
G03X763779Y817520I3937J0D01*
G01X767716Y855118D02*
Y829331D01*
G01X759842Y921260D02*
Y821457D01*
G01X771653Y825394D02*
X791338D01*
G01X793307Y817520D02*
X763779D01*
G01X793307Y789174D02*
X765945D01*
G01X793307Y781693D02*
X765945D01*
G01X767716Y855118D02*
G03X759842I-3937J0D01*
G01Y885827D02*
G03X767716I3937J0D01*
G01Y929134D02*
Y885827D01*
G01X759842D02*
Y855118D01*
G01Y921260D02*
G03X755905Y925197I-3937J0D01*
G01X767716Y929134D02*
G03X763779Y933071I-3937J0D01*
G01X750000D02*
G03Y925197I0J-3937D01*
G01X719291D02*
G03Y933071I0J3937D01*
G01X759842Y921260D02*
G03X755905Y925197I-3937J0D01*
G01X750000Y933071D02*
X763779D01*
G01X750000Y925197D02*
X719291D01*
G01X791338Y-35433D02*
G03X795275Y-31496I0J3937D01*
G01D02*
Y316339D01*
G01D02*
G03X791338Y320276I-3937J0D01*
G01X795275Y370276D02*
Y330118D01*
G01D02*
X793307Y328150D01*
G01X795275Y658071D02*
Y381693D01*
G01D02*
X793307Y379725D01*
G01X795275Y370276D02*
X793307Y372244D01*
G01X795275Y658071D02*
X793307Y660040D01*
G01X795275Y779725D02*
Y739567D01*
G01D02*
X793307Y737599D01*
G01X791338Y825394D02*
G03X795275Y829331I0J3937D01*
G01D02*
Y956693D01*
G01Y815552D02*
Y791142D01*
G01Y815552D02*
X793307Y817520D01*
G01X795275Y779725D02*
X793307Y781693D01*
G01X795275Y791142D02*
X793307Y789174D01*
G01X795275Y956693D02*
G03X791338Y960630I-3937J0D01*
M02*
